(kicad_pcb
	(version 20260206)
	(generator "pcbnew")
	(generator_version "10.0")
	(general
		(thickness 1.6)
		(legacy_teardrops no)
	)
	(paper "A4")
	(title_block
		(title "v1-pdb — T6M_PDB_D_0927_0900.brd")
		(comment 1 "Open CloudServer (Microsoft) / footprint 309 of 321 (J14), pads 1-46 of 46")
	)
	(layers
		(0 "F.Cu" signal "TOP")
		(4 "In1.Cu" signal "GND")
		(6 "In2.Cu" signal "IN1")
		(8 "In3.Cu" signal "VCC")
		(10 "In4.Cu" signal "VCC1")
		(12 "In5.Cu" signal "IN2")
		(14 "In6.Cu" signal "GND1")
		(2 "B.Cu" signal "BOTTOM")
		(9 "F.Adhes" user "F.Adhesive")
		(11 "B.Adhes" user "B.Adhesive")
		(13 "F.Paste" user "Package Geometry/Pastemask Top")
		(15 "B.Paste" user "Package Geometry/Pastemask Bottom")
		(5 "F.SilkS" user "Ref Des/Silkscreen Top")
		(7 "B.SilkS" user "Ref Des/Silkscreen Bottom")
		(1 "F.Mask" user "Board Geometry/Soldermask Top")
		(3 "B.Mask" user "Board Geometry/Soldermask Bottom")
		(17 "Dwgs.User" user "User.Drawings")
		(19 "Cmts.User" user "User.Comments")
		(21 "Eco1.User" user "User.Eco1")
		(23 "Eco2.User" user "User.Eco2")
		(25 "Edge.Cuts" user "Board Geometry/Outline")
		(27 "Margin" user)
		(31 "F.CrtYd" user "Package Geometry/Place Bound Top")
		(29 "B.CrtYd" user "Package Geometry/Place Bound Bottom")
		(35 "F.Fab" user "Ref Des/Assembly Top")
		(33 "B.Fab" user "Ref Des/Assembly Bottom")
	)
	(footprint ""
		(layer "B.Cu")
		(at 44.03979 -319.41008 90)
		(property "Reference" "J14"
			(at 6.291834 -4.21005 0)
			(unlocked yes)
			(layer "B.SilkS")
			(effects
				(font
					(size 0.7874 0.5842)
					(thickness 0.1524)
				)
				(justify left mirror)
			)
		)
		(property "Value" ""
			(at 0 0 90)
			(layer "B.Fab")
			(effects
				(font
					(size 1.27 1.27)
				)
				(justify mirror)
			)
		)
		(duplicate_pad_numbers_are_jumpers no)
		(pad "" np_thru_hole circle
			(at -1.35001 -2.54)
			(size 2.5146 2.5146)
			(drill 2.5146)
			(layers "*.Cu" "*.Mask")
			(clearance 0.381)
			(thermal_gap 0.381)
		)
		(pad "" np_thru_hole circle
			(at 0 50.8)
			(size 2.5146 2.5146)
			(drill 2.5146)
			(layers "*.Cu" "*.Mask")
			(clearance 0.381)
			(thermal_gap 0.381)
		)
		(pad "P1" thru_hole rect
			(at 0 0)
			(size 1.1684 1.1684)
			(drill 0.762)
			(layers "*.Cu" "*.Mask")
			(remove_unused_layers no)
			(net "GND")
			(clearance 0.0508)
			(padstack
				(mode front_inner_back)
				(layer "Inner"
					(shape circle)
					(size 1.1684 1.1684)
					(clearance 0.0508)
				)
				(layer "B.Cu"
					(shape rect)
					(size 1.1684 1.1684)
					(thermal_gap 0.0508)
					(clearance 0.0508)
				)
			)
		)
		(pad "P2" thru_hole circle
			(at 0 2.54)
			(size 1.1684 1.1684)
			(drill 0.762)
			(layers "*.Cu" "*.Mask")
			(remove_unused_layers no)
			(net "GND")
			(clearance 0.0508)
			(thermal_gap 0.0508)
		)
		(pad "P3" thru_hole circle
			(at 0 5.08)
			(size 1.1684 1.1684)
			(drill 0.762)
			(layers "*.Cu" "*.Mask")
			(remove_unused_layers no)
			(net "GND")
			(clearance 0.0508)
			(thermal_gap 0.0508)
		)
		(pad "P4" thru_hole circle
			(at 0 7.62)
			(size 1.1684 1.1684)
			(drill 0.762)
			(layers "*.Cu" "*.Mask")
			(remove_unused_layers no)
			(net "GND")
			(clearance 0.0508)
			(thermal_gap 0.0508)
		)
		(pad "P5" thru_hole circle
			(at 0 10.16)
			(size 1.1684 1.1684)
			(drill 0.762)
			(layers "*.Cu" "*.Mask")
			(remove_unused_layers no)
			(net "GND")
			(clearance 0.0508)
			(thermal_gap 0.0508)
		)
		(pad "P6" thru_hole circle
			(at 0 12.7)
			(size 1.1684 1.1684)
			(drill 0.762)
			(layers "*.Cu" "*.Mask")
			(remove_unused_layers no)
			(net "GND")
			(clearance 0.0508)
			(thermal_gap 0.0508)
		)
		(pad "P7" thru_hole circle
			(at 0 15.24)
			(size 1.1684 1.1684)
			(drill 0.762)
			(layers "*.Cu" "*.Mask")
			(remove_unused_layers no)
			(net "GND")
			(clearance 0.0508)
			(thermal_gap 0.0508)
		)
		(pad "P8" thru_hole circle
			(at 0 17.78)
			(size 1.1684 1.1684)
			(drill 0.762)
			(layers "*.Cu" "*.Mask")
			(remove_unused_layers no)
			(net "GND")
			(clearance 0.0508)
			(thermal_gap 0.0508)
		)
		(pad "P9" thru_hole circle
			(at 0 20.32)
			(size 1.1684 1.1684)
			(drill 0.762)
			(layers "*.Cu" "*.Mask")
			(remove_unused_layers no)
			(net "P12V")
			(clearance 0.0508)
			(thermal_gap 0.0508)
		)
		(pad "P10" thru_hole circle
			(at 0 22.86)
			(size 1.1684 1.1684)
			(drill 0.762)
			(layers "*.Cu" "*.Mask")
			(remove_unused_layers no)
			(net "P12V")
			(clearance 0.0508)
			(thermal_gap 0.0508)
		)
		(pad "P11" thru_hole circle
			(at 0 25.4)
			(size 1.1684 1.1684)
			(drill 0.762)
			(layers "*.Cu" "*.Mask")
			(remove_unused_layers no)
			(net "P12V")
			(clearance 0.0508)
			(thermal_gap 0.0508)
		)
		(pad "P12" thru_hole circle
			(at 0 27.94)
			(size 1.1684 1.1684)
			(drill 0.762)
			(layers "*.Cu" "*.Mask")
			(remove_unused_layers no)
			(net "P12V")
			(clearance 0.0508)
			(thermal_gap 0.0508)
		)
		(pad "P13" thru_hole circle
			(at 0 30.48)
			(size 1.1684 1.1684)
			(drill 0.762)
			(layers "*.Cu" "*.Mask")
			(remove_unused_layers no)
			(net "P12V")
			(clearance 0.0508)
			(thermal_gap 0.0508)
		)
		(pad "P14" thru_hole circle
			(at 0 33.02)
			(size 1.1684 1.1684)
			(drill 0.762)
			(layers "*.Cu" "*.Mask")
			(remove_unused_layers no)
			(net "P12V")
			(clearance 0.0508)
			(thermal_gap 0.0508)
		)
		(pad "P15" thru_hole circle
			(at 0 35.56)
			(size 1.1684 1.1684)
			(drill 0.762)
			(layers "*.Cu" "*.Mask")
			(remove_unused_layers no)
			(net "P12V")
			(clearance 0.0508)
			(thermal_gap 0.0508)
		)
		(pad "P16" thru_hole circle
			(at 0 38.1)
			(size 1.1684 1.1684)
			(drill 0.762)
			(layers "*.Cu" "*.Mask")
			(remove_unused_layers no)
			(net "P12V")
			(clearance 0.0508)
			(thermal_gap 0.0508)
		)
		(pad "P17" thru_hole circle
			(at -2.70002 38.1)
			(size 1.1684 1.1684)
			(drill 0.762)
			(layers "*.Cu" "*.Mask")
			(remove_unused_layers no)
			(net "P12V")
			(clearance 0.0508)
			(thermal_gap 0.0508)
		)
		(pad "P18" thru_hole circle
			(at -2.70002 35.56)
			(size 1.1684 1.1684)
			(drill 0.762)
			(layers "*.Cu" "*.Mask")
			(remove_unused_layers no)
			(net "P12V")
			(clearance 0.0508)
			(thermal_gap 0.0508)
		)
		(pad "P19" thru_hole circle
			(at -2.70002 33.02)
			(size 1.1684 1.1684)
			(drill 0.762)
			(layers "*.Cu" "*.Mask")
			(remove_unused_layers no)
			(net "P12V")
			(clearance 0.0508)
			(thermal_gap 0.0508)
		)
		(pad "P20" thru_hole circle
			(at -2.70002 30.48)
			(size 1.1684 1.1684)
			(drill 0.762)
			(layers "*.Cu" "*.Mask")
			(remove_unused_layers no)
			(net "P12V")
			(clearance 0.0508)
			(thermal_gap 0.0508)
		)
		(pad "P21" thru_hole circle
			(at -2.70002 27.94)
			(size 1.1684 1.1684)
			(drill 0.762)
			(layers "*.Cu" "*.Mask")
			(remove_unused_layers no)
			(net "P12V")
			(clearance 0.0508)
			(thermal_gap 0.0508)
		)
		(pad "P22" thru_hole circle
			(at -2.70002 25.4)
			(size 1.1684 1.1684)
			(drill 0.762)
			(layers "*.Cu" "*.Mask")
			(remove_unused_layers no)
			(net "P12V")
			(clearance 0.0508)
			(thermal_gap 0.0508)
		)
		(pad "P23" thru_hole circle
			(at -2.70002 22.86)
			(size 1.1684 1.1684)
			(drill 0.762)
			(layers "*.Cu" "*.Mask")
			(remove_unused_layers no)
			(net "P12V")
			(clearance 0.0508)
			(thermal_gap 0.0508)
		)
		(pad "P24" thru_hole circle
			(at -2.70002 20.32)
			(size 1.1684 1.1684)
			(drill 0.762)
			(layers "*.Cu" "*.Mask")
			(remove_unused_layers no)
			(net "P12V")
			(clearance 0.0508)
			(thermal_gap 0.0508)
		)
		(pad "P25" thru_hole circle
			(at -2.70002 17.78)
			(size 1.1684 1.1684)
			(drill 0.762)
			(layers "*.Cu" "*.Mask")
			(remove_unused_layers no)
			(net "GND")
			(clearance 0.0508)
			(thermal_gap 0.0508)
		)
		(pad "P26" thru_hole circle
			(at -2.70002 15.24)
			(size 1.1684 1.1684)
			(drill 0.762)
			(layers "*.Cu" "*.Mask")
			(remove_unused_layers no)
			(net "GND")
			(clearance 0.0508)
			(thermal_gap 0.0508)
		)
		(pad "P27" thru_hole circle
			(at -2.70002 12.7)
			(size 1.1684 1.1684)
			(drill 0.762)
			(layers "*.Cu" "*.Mask")
			(remove_unused_layers no)
			(net "GND")
			(clearance 0.0508)
			(thermal_gap 0.0508)
		)
		(pad "P28" thru_hole circle
			(at -2.70002 10.16)
			(size 1.1684 1.1684)
			(drill 0.762)
			(layers "*.Cu" "*.Mask")
			(remove_unused_layers no)
			(net "GND")
			(clearance 0.0508)
			(thermal_gap 0.0508)
		)
		(pad "P29" thru_hole circle
			(at -2.70002 7.62)
			(size 1.1684 1.1684)
			(drill 0.762)
			(layers "*.Cu" "*.Mask")
			(remove_unused_layers no)
			(net "GND")
			(clearance 0.0508)
			(thermal_gap 0.0508)
		)
		(pad "P30" thru_hole circle
			(at -2.70002 5.08)
			(size 1.1684 1.1684)
			(drill 0.762)
			(layers "*.Cu" "*.Mask")
			(remove_unused_layers no)
			(net "GND")
			(clearance 0.0508)
			(thermal_gap 0.0508)
		)
		(pad "P31" thru_hole circle
			(at -2.70002 2.54)
			(size 1.1684 1.1684)
			(drill 0.762)
			(layers "*.Cu" "*.Mask")
			(remove_unused_layers no)
			(net "GND")
			(clearance 0.0508)
			(thermal_gap 0.0508)
		)
		(pad "P32" thru_hole circle
			(at -2.70002 0)
			(size 1.1684 1.1684)
			(drill 0.762)
			(layers "*.Cu" "*.Mask")
			(remove_unused_layers no)
			(net "GND")
			(clearance 0.0508)
			(thermal_gap 0.0508)
		)
		(pad "S1" thru_hole circle
			(at 0.55499 41.60012)
			(size 1.1684 1.1684)
			(drill 0.762)
			(layers "*.Cu" "*.Mask")
			(remove_unused_layers no)
			(net "T8_BLAD1_TXD")
			(clearance 0.0508)
			(thermal_gap 0.0508)
		)
		(pad "S2" thru_hole circle
			(at -0.71501 42.87012)
			(size 1.1684 1.1684)
			(drill 0.762)
			(layers "*.Cu" "*.Mask")
			(remove_unused_layers no)
			(net "T8_BLAD1_RXD")
			(clearance 0.0508)
			(thermal_gap 0.0508)
		)
		(pad "S3" thru_hole circle
			(at 0.55499 44.14012)
			(size 1.1684 1.1684)
			(drill 0.762)
			(layers "*.Cu" "*.Mask")
			(remove_unused_layers no)
			(net "T8_BLAD1_EN")
			(clearance 0.0508)
			(thermal_gap 0.0508)
		)
		(pad "S4" thru_hole circle
			(at -0.71501 45.41012)
			(size 1.1684 1.1684)
			(drill 0.762)
			(layers "*.Cu" "*.Mask")
			(remove_unused_layers no)
			(net "T8_BLAD2_EN")
			(clearance 0.0508)
			(thermal_gap 0.0508)
		)
		(pad "S5" thru_hole circle
			(at 0.55499 46.68012)
			(size 1.1684 1.1684)
			(drill 0.762)
			(layers "*.Cu" "*.Mask")
			(remove_unused_layers no)
			(net "T8_BLAD2_TXD")
			(clearance 0.0508)
			(thermal_gap 0.0508)
		)
		(pad "S6" thru_hole circle
			(at -0.71501 47.95012)
			(size 1.1684 1.1684)
			(drill 0.762)
			(layers "*.Cu" "*.Mask")
			(remove_unused_layers no)
			(net "T8_BLAD2_RXD")
			(clearance 0.0508)
			(thermal_gap 0.0508)
		)
		(pad "S7" thru_hole circle
			(at -3.25501 47.95012)
			(size 1.1684 1.1684)
			(drill 0.762)
			(layers "*.Cu" "*.Mask")
			(remove_unused_layers no)
			(net "T8_BLAD4_RXD")
			(clearance 0.0508)
			(thermal_gap 0.0508)
		)
		(pad "S8" thru_hole circle
			(at -1.98501 46.68012)
			(size 1.1684 1.1684)
			(drill 0.762)
			(layers "*.Cu" "*.Mask")
			(remove_unused_layers no)
			(net "T8_BLAD4_TXD")
			(clearance 0.0508)
			(thermal_gap 0.0508)
		)
		(pad "S9" thru_hole circle
			(at -3.25501 45.41012)
			(size 1.1684 1.1684)
			(drill 0.762)
			(layers "*.Cu" "*.Mask")
			(remove_unused_layers no)
			(net "T8_BLAD4_EN")
			(clearance 0.0508)
			(thermal_gap 0.0508)
		)
		(pad "S10" thru_hole circle
			(at -1.98501 44.14012)
			(size 1.1684 1.1684)
			(drill 0.762)
			(layers "*.Cu" "*.Mask")
			(remove_unused_layers no)
			(net "T8_BLAD3_EN")
			(clearance 0.0508)
			(thermal_gap 0.0508)
		)
		(pad "S11" thru_hole circle
			(at -3.25501 42.87012)
			(size 1.1684 1.1684)
			(drill 0.762)
			(layers "*.Cu" "*.Mask")
			(remove_unused_layers no)
			(net "T8_BLAD3_RXD")
			(clearance 0.0508)
			(thermal_gap 0.0508)
		)
		(pad "S12" thru_hole circle
			(at -1.98501 41.60012)
			(size 1.1684 1.1684)
			(drill 0.762)
			(layers "*.Cu" "*.Mask")
			(remove_unused_layers no)
			(net "T8_BLAD3_TXD")
			(clearance 0.0508)
			(thermal_gap 0.0508)
		)
	)
)
